# T6G (Grand Teton) — schematic netlist excerpt (pin names and nets, part order shuffled) for the footprints in the layout excerpt that follows; sources: Cadence DE-HDL packaged netlist, KiCad conversion of 04192023_DAF0TMB3IC0_F0TG_MB_C_brd_V02_OCP.brd

PC86_2  Q_CAP  0.1UF 25V 10% X7R  pkg 0402  page 201 : A = SW_P12V_AUX_PVDDCR_CPU1_P0_FLT ; B = GND
R3499  Q_RES  0 5% CHIP  pkg 0402LF  page 245 : A = GPU_BASE_ID1 ; B = GPU_BASE_ID1_R

(kicad_pcb
	(version 20260206)
	(generator "pcbnew")
	(generator_version "10.0")
	(general
		(thickness 1.6)
		(legacy_teardrops no)
	)
	(paper "A4")
	(title_block
		(title "04192023_DAF0TMB3IC0_F0TG_MB_C_brd_V02_OCP.brd")
		(comment 1 "Grand Teton / footprints 2441-2442 of 8354")
	)
	(layers
		(0 "F.Cu" signal "TOP")
		(4 "In1.Cu" signal "GND")
		(6 "In2.Cu" signal "IN1")
		(8 "In3.Cu" signal "GND1")
		(10 "In4.Cu" signal "IN2")
		(12 "In5.Cu" signal "GND2")
		(14 "In6.Cu" signal "IN3")
		(16 "In7.Cu" signal "GND3")
		(18 "In8.Cu" signal "VCC")
		(20 "In9.Cu" signal "VCC1")
		(22 "In10.Cu" signal "GND4")
		(24 "In11.Cu" signal "IN4")
		(26 "In12.Cu" signal "GND5")
		(28 "In13.Cu" signal "IN5")
		(30 "In14.Cu" signal "GND6")
		(32 "In15.Cu" signal "IN6")
		(34 "In16.Cu" signal "GND7")
		(2 "B.Cu" signal "BOTTOM")
		(9 "F.Adhes" user "F.Adhesive")
		(11 "B.Adhes" user "B.Adhesive")
		(13 "F.Paste" user "Package Geometry/Pastemask Top")
		(15 "B.Paste" user "Package Geometry/Pastemask Bottom")
		(5 "F.SilkS" user "Ref Des/Silkscreen Top")
		(7 "B.SilkS" user "Ref Des/Silkscreen Bottom")
		(1 "F.Mask" user "Board Geometry/Soldermask Top")
		(3 "B.Mask" user "Board Geometry/Soldermask Bottom")
		(17 "Dwgs.User" user "User.Drawings")
		(19 "Cmts.User" user "User.Comments")
		(21 "Eco1.User" user "User.Eco1")
		(23 "Eco2.User" user "User.Eco2")
		(25 "Edge.Cuts" user "Board Geometry/Outline")
		(27 "Margin" user)
		(31 "F.CrtYd" user "Package Geometry/Place Bound Top")
		(29 "B.CrtYd" user "Package Geometry/Place Bound Bottom")
		(35 "F.Fab" user "Ref Des/Assembly Top")
		(33 "B.Fab" user "Ref Des/Assembly Bottom")
	)
	(footprint ""
		(layer "F.Cu")
		(at 187.316618 -427.255178 -90)
		(property "Reference" "R3499"
			(at 0 0 270)
			(layer "F.SilkS")
			(hide yes)
			(effects
				(font
					(size 1.27 1.27)
				)
			)
		)
		(property "Value" ""
			(at 0 0 270)
			(layer "F.Fab")
			(effects
				(font
					(size 1.27 1.27)
				)
			)
		)
		(duplicate_pad_numbers_are_jumpers no)
		(fp_line
			(start -0.7874 0.4064)
			(end -0.7874 -0.4064)
			(stroke
				(width 0.1524)
				(type default)
			)
			(layer "F.SilkS")
		)
		(fp_line
			(start 0.7874 0.4064)
			(end -0.7874 0.4064)
			(stroke
				(width 0.1524)
				(type default)
			)
			(layer "F.SilkS")
		)
		(fp_line
			(start -0.7874 -0.4064)
			(end 0.7874 -0.4064)
			(stroke
				(width 0.1524)
				(type default)
			)
			(layer "F.SilkS")
		)
		(fp_line
			(start 0.7874 -0.4064)
			(end 0.7874 0.4064)
			(stroke
				(width 0.1524)
				(type default)
			)
			(layer "F.SilkS")
		)
		(fp_line
			(start -0.67945 0.3048)
			(end -0.67945 -0.305054)
			(stroke
				(width 0.1)
				(type default)
			)
			(layer "F.Fab")
		)
		(fp_line
			(start -0.12065 0.3048)
			(end -0.67945 0.3048)
			(stroke
				(width 0.1)
				(type default)
			)
			(layer "F.Fab")
		)
		(fp_line
			(start 0.120396 0.3048)
			(end 0.120396 0.2794)
			(stroke
				(width 0.1)
				(type default)
			)
			(layer "F.Fab")
		)
		(fp_line
			(start 0.67945 0.3048)
			(end 0.120396 0.3048)
			(stroke
				(width 0.1)
				(type default)
			)
			(layer "F.Fab")
		)
		(fp_line
			(start -0.12065 0.2794)
			(end -0.12065 0.3048)
			(stroke
				(width 0.1)
				(type default)
			)
			(layer "F.Fab")
		)
		(fp_line
			(start 0.120396 0.2794)
			(end -0.12065 0.2794)
			(stroke
				(width 0.1)
				(type default)
			)
			(layer "F.Fab")
		)
		(fp_line
			(start -0.12065 -0.2794)
			(end 0.12065 -0.2794)
			(stroke
				(width 0.1)
				(type default)
			)
			(layer "F.Fab")
		)
		(fp_line
			(start 0.12065 -0.2794)
			(end 0.12065 -0.3048)
			(stroke
				(width 0.1)
				(type default)
			)
			(layer "F.Fab")
		)
		(fp_line
			(start 0.12065 -0.3048)
			(end 0.67945 -0.3048)
			(stroke
				(width 0.1)
				(type default)
			)
			(layer "F.Fab")
		)
		(fp_line
			(start 0.67945 -0.3048)
			(end 0.67945 0.3048)
			(stroke
				(width 0.1)
				(type default)
			)
			(layer "F.Fab")
		)
		(fp_line
			(start -0.67945 -0.305054)
			(end -0.12065 -0.305054)
			(stroke
				(width 0.1)
				(type default)
			)
			(layer "F.Fab")
		)
		(fp_line
			(start -0.12065 -0.305054)
			(end -0.12065 -0.2794)
			(stroke
				(width 0.1)
				(type default)
			)
			(layer "F.Fab")
		)
		(pad "1" smd circle
			(at -0.40005 0 270)
			(size 0 0)
			(layers "F.Cu" "F.Mask" "F.Paste")
			(net "GPU_BASE_ID1")
		)
		(pad "2" smd circle
			(at 0.40005 0 270)
			(size 0 0)
			(layers "F.Cu" "F.Mask" "F.Paste")
			(net "GPU_BASE_ID1_R")
		)
	)
	(footprint ""
		(layer "F.Cu")
		(at 322.565268 -339.372448)
		(property "Reference" "PC86_2"
			(at 0 0 0)
			(layer "F.SilkS")
			(hide yes)
			(effects
				(font
					(size 1.27 1.27)
				)
			)
		)
		(property "Value" ""
			(at 0 0 0)
			(layer "F.Fab")
			(effects
				(font
					(size 1.27 1.27)
				)
			)
		)
		(duplicate_pad_numbers_are_jumpers no)
		(fp_line
			(start -0.7874 -0.4064)
			(end 0.7874 -0.4064)
			(stroke
				(width 0.1524)
				(type default)
			)
			(layer "F.SilkS")
		)
		(fp_line
			(start -0.7874 0.4064)
			(end -0.7874 -0.4064)
			(stroke
				(width 0.1524)
				(type default)
			)
			(layer "F.SilkS")
		)
		(fp_line
			(start 0.7874 -0.4064)
			(end 0.7874 0.4064)
			(stroke
				(width 0.1524)
				(type default)
			)
			(layer "F.SilkS")
		)
		(fp_line
			(start 0.7874 0.4064)
			(end -0.7874 0.4064)
			(stroke
				(width 0.1524)
				(type default)
			)
			(layer "F.SilkS")
		)
		(fp_line
			(start -0.67945 -0.305054)
			(end -0.12065 -0.305054)
			(stroke
				(width 0.1)
				(type default)
			)
			(layer "F.Fab")
		)
		(fp_line
			(start -0.67945 0.3048)
			(end -0.67945 -0.305054)
			(stroke
				(width 0.1)
				(type default)
			)
			(layer "F.Fab")
		)
		(fp_line
			(start -0.12065 -0.305054)
			(end -0.12065 -0.2794)
			(stroke
				(width 0.1)
				(type default)
			)
			(layer "F.Fab")
		)
		(fp_line
			(start -0.12065 -0.2794)
			(end 0.12065 -0.2794)
			(stroke
				(width 0.1)
				(type default)
			)
			(layer "F.Fab")
		)
		(fp_line
			(start -0.12065 0.2794)
			(end -0.12065 0.3048)
			(stroke
				(width 0.1)
				(type default)
			)
			(layer "F.Fab")
		)
		(fp_line
			(start -0.12065 0.3048)
			(end -0.67945 0.3048)
			(stroke
				(width 0.1)
				(type default)
			)
			(layer "F.Fab")
		)
		(fp_line
			(start 0.120396 0.2794)
			(end -0.12065 0.2794)
			(stroke
				(width 0.1)
				(type default)
			)
			(layer "F.Fab")
		)
		(fp_line
			(start 0.120396 0.3048)
			(end 0.120396 0.2794)
			(stroke
				(width 0.1)
				(type default)
			)
			(layer "F.Fab")
		)
		(fp_line
			(start 0.12065 -0.3048)
			(end 0.67945 -0.3048)
			(stroke
				(width 0.1)
				(type default)
			)
			(layer "F.Fab")
		)
		(fp_line
			(start 0.12065 -0.2794)
			(end 0.12065 -0.3048)
			(stroke
				(width 0.1)
				(type default)
			)
			(layer "F.Fab")
		)
		(fp_line
			(start 0.67945 -0.3048)
			(end 0.67945 0.3048)
			(stroke
				(width 0.1)
				(type default)
			)
			(layer "F.Fab")
		)
		(fp_line
			(start 0.67945 0.3048)
			(end 0.120396 0.3048)
			(stroke
				(width 0.1)
				(type default)
			)
			(layer "F.Fab")
		)
		(pad "1" smd circle
			(at -0.40005 0)
			(size 0 0)
			(layers "F.Cu" "F.Mask" "F.Paste")
			(net "SW_P12V_AUX_PVDDCR_CPU1_P0_FLT")
		)
		(pad "2" smd circle
			(at 0.40005 0)
			(size 0 0)
			(layers "F.Cu" "F.Mask" "F.Paste")
			(net "GND")
		)
	)
)
